(kicad_pcb
	(version 20260206)
	(generator "pcbnew")
	(generator_version "10.0")
	(general
		(thickness 1.6)
		(legacy_teardrops no)
	)
	(paper "A4")
	(title_block
		(title "peb — Lightning_PEB_BRD.brd")
		(comment 1 "Lightning (Wiwynn / Facebook NVMe JBOF) / footprints 2310-2318 of 2563")
	)
	(layers
		(0 "F.Cu" signal "TOP")
		(4 "In1.Cu" signal "L2GND")
		(6 "In2.Cu" signal "L3")
		(8 "In3.Cu" signal "L4VCC")
		(10 "In4.Cu" signal "L5VCC")
		(12 "In5.Cu" signal "L6")
		(14 "In6.Cu" signal "L7GND")
		(2 "B.Cu" signal "BOTTOM")
		(9 "F.Adhes" user "F.Adhesive")
		(11 "B.Adhes" user "B.Adhesive")
		(13 "F.Paste" user "Package Geometry/Pastemask Top")
		(15 "B.Paste" user "Package Geometry/Pastemask Bottom")
		(5 "F.SilkS" user "Ref Des/Silkscreen Top")
		(7 "B.SilkS" user "Ref Des/Silkscreen Bottom")
		(1 "F.Mask" user "Board Geometry/Soldermask Top")
		(3 "B.Mask" user "Board Geometry/Soldermask Bottom")
		(17 "Dwgs.User" user "User.Drawings")
		(19 "Cmts.User" user "User.Comments")
		(21 "Eco1.User" user "User.Eco1")
		(23 "Eco2.User" user "User.Eco2")
		(25 "Edge.Cuts" user "Board Geometry/Outline")
		(27 "Margin" user)
		(31 "F.CrtYd" user "Package Geometry/Place Bound Top")
		(29 "B.CrtYd" user "Package Geometry/Place Bound Bottom")
		(35 "F.Fab" user "Ref Des/Assembly Top")
		(33 "B.Fab" user "Ref Des/Assembly Bottom")
	)
	(footprint ""
		(layer "B.Cu")
		(at 130.4798 -196.3928)
		(property "Reference" "R4123"
			(at 0 0 0)
			(layer "B.SilkS")
			(hide yes)
			(effects
				(font
					(size 1.27 1.27)
				)
				(justify mirror)
			)
		)
		(property "Value" "4K7R2F-GP"
			(at -0.064008 -3.993896 0)
			(unlocked yes)
			(layer "B.Fab")
			(hide yes)
			(effects
				(font
					(size 1.016 1.016)
					(thickness 0.1524)
				)
				(justify mirror)
			)
		)
		(property "Device Type" "R402H16"
			(at -0.064008 -5.517896 0)
			(unlocked yes)
			(layer "B.Fab")
			(hide yes)
			(effects
				(font
					(size 1.016 1.016)
					(thickness 0.1524)
				)
				(justify mirror)
			)
		)
		(duplicate_pad_numbers_are_jumpers no)
		(fp_line
			(start -0.508 -0.9398)
			(end 0.508 -0.9398)
			(stroke
				(width 0.1524)
				(type default)
			)
			(layer "B.SilkS")
		)
		(fp_line
			(start 0.508 -0.9398)
			(end 0.508 0.9398)
			(stroke
				(width 0.1524)
				(type default)
			)
			(layer "B.SilkS")
		)
		(fp_rect
			(start 0.508 0.9398)
			(end -0.508 -0.9398)
			(stroke
				(width 0)
				(type default)
			)
			(fill no)
			(layer "B.CrtYd")
		)
		(fp_rect
			(start 0.508 0.9398)
			(end -0.508 -0.9398)
			(stroke
				(width 0)
				(type default)
			)
			(fill no)
			(layer "B.Fab")
		)
		(pad "1" smd custom
			(at 0 -0.4445 180)
			(size 0.1397 0.1397)
			(layers "B.Cu" "B.Mask" "B.Paste")
			(net "SSD_PERST#1")
			(options
				(clearance outline)
				(anchor circle)
			)
			(primitives
				(gr_poly
					(pts
						(arc
							(start -0.1778 0.2794)
							(mid -0.249642 0.249642)
							(end -0.2794 0.1778)
						)
						(arc
							(start -0.2794 -0.1778)
							(mid -0.249642 -0.249642)
							(end -0.1778 -0.2794)
						)
						(arc
							(start 0.1778 -0.2794)
							(mid 0.249642 -0.249642)
							(end 0.2794 -0.1778)
						)
						(arc
							(start 0.2794 0.1778)
							(mid 0.249642 0.249642)
							(end 0.1778 0.2794)
						)
					)
					(width 0)
					(fill yes)
				)
			)
		)
		(pad "2" smd custom
			(at 0 0.4445 180)
			(size 0.1397 0.1397)
			(layers "B.Cu" "B.Mask" "B.Paste")
			(net "P3V3_STBY")
			(options
				(clearance outline)
				(anchor circle)
			)
			(primitives
				(gr_poly
					(pts
						(arc
							(start -0.1778 0.2794)
							(mid -0.249642 0.249642)
							(end -0.2794 0.1778)
						)
						(arc
							(start -0.2794 -0.1778)
							(mid -0.249642 -0.249642)
							(end -0.1778 -0.2794)
						)
						(arc
							(start 0.1778 -0.2794)
							(mid 0.249642 -0.249642)
							(end 0.2794 -0.1778)
						)
						(arc
							(start 0.2794 0.1778)
							(mid 0.249642 0.249642)
							(end 0.1778 0.2794)
						)
					)
					(width 0)
					(fill yes)
				)
			)
		)
	)
	(footprint ""
		(layer "B.Cu")
		(at 253.5936 -39.0144 90)
		(property "Reference" "C591"
			(at 0 0 90)
			(layer "B.SilkS")
			(hide yes)
			(effects
				(font
					(size 1.27 1.27)
				)
				(justify mirror)
			)
		)
		(property "Value" "SCD1U16V1KX-1-GP"
			(at 2.8321 -1.7399 90)
			(unlocked yes)
			(layer "B.Fab")
			(hide yes)
			(effects
				(font
					(size 1.016 1.016)
					(thickness 0.1524)
				)
				(justify mirror)
			)
		)
		(property "Device Type" "C0201H13"
			(at 2.8321 -3.2639 90)
			(unlocked yes)
			(layer "B.Fab")
			(hide yes)
			(effects
				(font
					(size 1.016 1.016)
					(thickness 0.1524)
				)
				(justify mirror)
			)
		)
		(duplicate_pad_numbers_are_jumpers no)
		(fp_rect
			(start 0.2794 0.6477)
			(end -0.2794 -0.6477)
			(stroke
				(width 0)
				(type default)
			)
			(fill no)
			(layer "B.CrtYd")
		)
		(fp_rect
			(start 0.2794 0.6477)
			(end -0.2794 -0.6477)
			(stroke
				(width 0)
				(type default)
			)
			(fill no)
			(layer "B.Fab")
		)
		(pad "1" smd custom
			(at 0 -0.2794 270)
			(size 0.0762 0.0762)
			(layers "B.Cu" "B.Mask" "B.Paste")
			(net "DUT_AVD_PCIE")
			(options
				(clearance outline)
				(anchor circle)
			)
			(primitives
				(gr_poly
					(pts
						(arc
							(start 0.1524 0.127)
							(mid 0.137521 0.162921)
							(end 0.1016 0.1778)
						)
						(arc
							(start -0.1016 0.1778)
							(mid -0.137521 0.162921)
							(end -0.1524 0.127)
						)
						(arc
							(start -0.1524 -0.127)
							(mid -0.137521 -0.162921)
							(end -0.1016 -0.1778)
						)
						(arc
							(start 0.1016 -0.1778)
							(mid 0.137521 -0.162921)
							(end 0.1524 -0.127)
						)
					)
					(width 0)
					(fill yes)
				)
			)
		)
		(pad "2" smd custom
			(at 0 0.2794 270)
			(size 0.0762 0.0762)
			(layers "B.Cu" "B.Mask" "B.Paste")
			(net "GND")
			(options
				(clearance outline)
				(anchor circle)
			)
			(primitives
				(gr_poly
					(pts
						(arc
							(start 0.1524 0.127)
							(mid 0.137521 0.162921)
							(end 0.1016 0.1778)
						)
						(arc
							(start -0.1016 0.1778)
							(mid -0.137521 0.162921)
							(end -0.1524 0.127)
						)
						(arc
							(start -0.1524 -0.127)
							(mid -0.137521 -0.162921)
							(end -0.1016 -0.1778)
						)
						(arc
							(start 0.1016 -0.1778)
							(mid 0.137521 -0.162921)
							(end 0.1524 -0.127)
						)
					)
					(width 0)
					(fill yes)
				)
			)
		)
	)
	(footprint ""
		(layer "B.Cu")
		(at 249.599958 -35.999928 -90)
		(property "Reference" "TP280"
			(at 0 0 90)
			(layer "B.SilkS")
			(hide yes)
			(effects
				(font
					(size 1.27 1.27)
				)
				(justify mirror)
			)
		)
		(property "Value" "TPAD28-2-GP"
			(at 0.0127 -1.6637 270)
			(unlocked yes)
			(layer "B.Fab")
			(hide yes)
			(effects
				(font
					(size 1.016 1.016)
					(thickness 0.1524)
				)
				(justify mirror)
			)
		)
		(property "Device Type" "TPAD28"
			(at 0.0127 -3.1877 270)
			(unlocked yes)
			(layer "B.Fab")
			(hide yes)
			(effects
				(font
					(size 1.016 1.016)
					(thickness 0.1524)
				)
				(justify mirror)
			)
		)
		(duplicate_pad_numbers_are_jumpers no)
		(fp_poly
			(pts
				(arc
					(start 0 -0.3556)
					(mid 0 0.3556)
					(end 0 -0.3556)
				)
			)
			(stroke
				(width 0)
				(type default)
			)
			(fill no)
			(layer "B.CrtYd")
		)
		(fp_poly
			(pts
				(arc
					(start 0 -0.6096)
					(mid 0 0.6096)
					(end 0 -0.6096)
				)
			)
			(stroke
				(width 0)
				(type default)
			)
			(fill no)
			(layer "B.Fab")
		)
		(pad "1" smd circle
			(at 0 0 90)
			(size 0.7112 0.7112)
			(layers "B.Cu" "B.Mask" "B.Paste")
			(net "TWI_SRST#1")
		)
	)
	(footprint ""
		(layer "B.Cu")
		(at 64.135 -46.99 90)
		(property "Reference" "PC22"
			(at 0 0 90)
			(layer "B.SilkS")
			(hide yes)
			(effects
				(font
					(size 1.27 1.27)
				)
				(justify mirror)
			)
		)
		(property "Value" "SC10U25V5KX-GP"
			(at 0.0762 -6.1214 90)
			(unlocked yes)
			(layer "B.Fab")
			(hide yes)
			(effects
				(font
					(size 1.016 1.016)
					(thickness 0.1524)
				)
				(justify mirror)
			)
		)
		(property "Device Type" "C805H56"
			(at 0.0762 -8.1534 90)
			(unlocked yes)
			(layer "B.Fab")
			(hide yes)
			(effects
				(font
					(size 1.016 1.016)
					(thickness 0.1524)
				)
				(justify mirror)
			)
		)
		(duplicate_pad_numbers_are_jumpers no)
		(fp_line
			(start -0.635 0)
			(end 0.635 0)
			(stroke
				(width 0.508)
				(type default)
			)
			(layer "B.SilkS")
		)
		(fp_rect
			(start 0.9652 1.778)
			(end -0.9652 -1.778)
			(stroke
				(width 0)
				(type default)
			)
			(fill no)
			(layer "B.CrtYd")
		)
		(fp_poly
			(pts
				(xy 0.9652 -1.778) (xy -0.9652 -1.778) (xy -0.9652 1.778) (xy 0.9652 1.778)
			)
			(stroke
				(width 0)
				(type default)
			)
			(fill no)
			(layer "B.Fab")
		)
		(pad "1" smd rect
			(at 0 -0.9652 270)
			(size 1.397 1.143)
			(layers "B.Cu" "B.Mask" "B.Paste")
			(net "P3V3_STBY_VIN")
		)
		(pad "2" smd rect
			(at 0 0.9652 270)
			(size 1.397 1.143)
			(layers "B.Cu" "B.Mask" "B.Paste")
			(net "GND")
		)
	)
	(footprint ""
		(layer "B.Cu")
		(at 161.417 -88.4174 180)
		(property "Reference" "C718"
			(at 0 0 0)
			(layer "B.SilkS")
			(hide yes)
			(effects
				(font
					(size 1.27 1.27)
				)
				(justify mirror)
			)
		)
		(property "Value" "SCD1U10V2KX-5GP"
			(at -1.1811 -2.7051 180)
			(unlocked yes)
			(layer "B.Fab")
			(hide yes)
			(effects
				(font
					(size 1.016 1.016)
					(thickness 0.1524)
				)
				(justify mirror)
			)
		)
		(property "Device Type" "C402H22"
			(at -1.1811 -4.2291 180)
			(unlocked yes)
			(layer "B.Fab")
			(hide yes)
			(effects
				(font
					(size 1.016 1.016)
					(thickness 0.1524)
				)
				(justify mirror)
			)
		)
		(duplicate_pad_numbers_are_jumpers no)
		(fp_rect
			(start 0.4318 0.9525)
			(end -0.4318 -0.9525)
			(stroke
				(width 0)
				(type default)
			)
			(fill no)
			(layer "B.CrtYd")
		)
		(fp_rect
			(start 0.4318 0.9525)
			(end -0.4318 -0.9525)
			(stroke
				(width 0)
				(type default)
			)
			(fill no)
			(layer "B.Fab")
		)
		(pad "1" smd custom
			(at 0 -0.4445)
			(size 0.1524 0.1524)
			(layers "B.Cu" "B.Mask" "B.Paste")
			(net "P1V8_CLKGEN")
			(options
				(clearance outline)
				(anchor circle)
			)
			(primitives
				(gr_poly
					(pts
						(arc
							(start 0.3048 0.2032)
							(mid 0.275042 0.275042)
							(end 0.2032 0.3048)
						)
						(arc
							(start -0.2032 0.3048)
							(mid -0.275042 0.275042)
							(end -0.3048 0.2032)
						)
						(arc
							(start -0.3048 -0.2032)
							(mid -0.275042 -0.275042)
							(end -0.2032 -0.3048)
						)
						(arc
							(start 0.2032 -0.3048)
							(mid 0.275042 -0.275042)
							(end 0.3048 -0.2032)
						)
					)
					(width 0)
					(fill yes)
				)
			)
		)
		(pad "2" smd custom
			(at 0 0.4445)
			(size 0.1524 0.1524)
			(layers "B.Cu" "B.Mask" "B.Paste")
			(net "GND")
			(options
				(clearance outline)
				(anchor circle)
			)
			(primitives
				(gr_poly
					(pts
						(arc
							(start 0.3048 0.2032)
							(mid 0.275042 0.275042)
							(end 0.2032 0.3048)
						)
						(arc
							(start -0.2032 0.3048)
							(mid -0.275042 0.275042)
							(end -0.3048 0.2032)
						)
						(arc
							(start -0.3048 -0.2032)
							(mid -0.275042 -0.275042)
							(end -0.2032 -0.3048)
						)
						(arc
							(start 0.2032 -0.3048)
							(mid 0.275042 -0.275042)
							(end 0.3048 -0.2032)
						)
					)
					(width 0)
					(fill yes)
				)
			)
		)
	)
	(footprint ""
		(layer "B.Cu")
		(at 340.995 -62.992 -90)
		(property "Reference" "PC174"
			(at 0 0 90)
			(layer "B.SilkS")
			(hide yes)
			(effects
				(font
					(size 1.27 1.27)
				)
				(justify mirror)
			)
		)
		(property "Value" "SC10U25V5KX-GP"
			(at 0.0762 -6.1214 270)
			(unlocked yes)
			(layer "B.Fab")
			(hide yes)
			(effects
				(font
					(size 1.016 1.016)
					(thickness 0.1524)
				)
				(justify mirror)
			)
		)
		(property "Device Type" "C805H56"
			(at 0.0762 -8.1534 270)
			(unlocked yes)
			(layer "B.Fab")
			(hide yes)
			(effects
				(font
					(size 1.016 1.016)
					(thickness 0.1524)
				)
				(justify mirror)
			)
		)
		(duplicate_pad_numbers_are_jumpers no)
		(fp_line
			(start -0.635 0)
			(end 0.635 0)
			(stroke
				(width 0.508)
				(type default)
			)
			(layer "B.SilkS")
		)
		(fp_rect
			(start 0.9652 1.778)
			(end -0.9652 -1.778)
			(stroke
				(width 0)
				(type default)
			)
			(fill no)
			(layer "B.CrtYd")
		)
		(fp_poly
			(pts
				(xy 0.9652 -1.778) (xy -0.9652 -1.778) (xy -0.9652 1.778) (xy 0.9652 1.778)
			)
			(stroke
				(width 0)
				(type default)
			)
			(fill no)
			(layer "B.Fab")
		)
		(pad "1" smd rect
			(at 0 -0.9652 90)
			(size 1.397 1.143)
			(layers "B.Cu" "B.Mask" "B.Paste")
			(net "P0V9_E_VIN")
		)
		(pad "2" smd rect
			(at 0 0.9652 90)
			(size 1.397 1.143)
			(layers "B.Cu" "B.Mask" "B.Paste")
			(net "GND")
		)
	)
	(footprint ""
		(layer "B.Cu")
		(at 132.125212 -205.849474)
		(property "Reference" "R3208"
			(at 0 0 0)
			(layer "B.SilkS")
			(hide yes)
			(effects
				(font
					(size 1.27 1.27)
				)
				(justify mirror)
			)
		)
		(property "Value" "0R2J-2-GP"
			(at -0.064008 -3.993896 0)
			(unlocked yes)
			(layer "B.Fab")
			(hide yes)
			(effects
				(font
					(size 1.016 1.016)
					(thickness 0.1524)
				)
				(justify mirror)
			)
		)
		(property "Device Type" "R402H16"
			(at -0.064008 -5.517896 0)
			(unlocked yes)
			(layer "B.Fab")
			(hide yes)
			(effects
				(font
					(size 1.016 1.016)
					(thickness 0.1524)
				)
				(justify mirror)
			)
		)
		(duplicate_pad_numbers_are_jumpers no)
		(fp_line
			(start -0.508 -0.9398)
			(end 0.508 -0.9398)
			(stroke
				(width 0.1524)
				(type default)
			)
			(layer "B.SilkS")
		)
		(fp_line
			(start 0.508 -0.9398)
			(end 0.508 0.9398)
			(stroke
				(width 0.1524)
				(type default)
			)
			(layer "B.SilkS")
		)
		(fp_rect
			(start 0.508 0.9398)
			(end -0.508 -0.9398)
			(stroke
				(width 0)
				(type default)
			)
			(fill no)
			(layer "B.CrtYd")
		)
		(fp_rect
			(start 0.508 0.9398)
			(end -0.508 -0.9398)
			(stroke
				(width 0)
				(type default)
			)
			(fill no)
			(layer "B.Fab")
		)
		(pad "1" smd custom
			(at 0 -0.4445 180)
			(size 0.1397 0.1397)
			(layers "B.Cu" "B.Mask" "B.Paste")
			(net "BMC_SSD_RST#2")
			(options
				(clearance outline)
				(anchor circle)
			)
			(primitives
				(gr_poly
					(pts
						(arc
							(start -0.1778 0.2794)
							(mid -0.249642 0.249642)
							(end -0.2794 0.1778)
						)
						(arc
							(start -0.2794 -0.1778)
							(mid -0.249642 -0.249642)
							(end -0.1778 -0.2794)
						)
						(arc
							(start 0.1778 -0.2794)
							(mid 0.249642 -0.249642)
							(end 0.2794 -0.1778)
						)
						(arc
							(start 0.2794 0.1778)
							(mid 0.249642 0.249642)
							(end 0.1778 0.2794)
						)
					)
					(width 0)
					(fill yes)
				)
			)
		)
		(pad "2" smd custom
			(at 0 0.4445 180)
			(size 0.1397 0.1397)
			(layers "B.Cu" "B.Mask" "B.Paste")
			(net "BMC_SSD_RST#0_A2")
			(options
				(clearance outline)
				(anchor circle)
			)
			(primitives
				(gr_poly
					(pts
						(arc
							(start -0.1778 0.2794)
							(mid -0.249642 0.249642)
							(end -0.2794 0.1778)
						)
						(arc
							(start -0.2794 -0.1778)
							(mid -0.249642 -0.249642)
							(end -0.1778 -0.2794)
						)
						(arc
							(start 0.1778 -0.2794)
							(mid 0.249642 -0.249642)
							(end 0.2794 -0.1778)
						)
						(arc
							(start 0.2794 0.1778)
							(mid 0.249642 0.249642)
							(end 0.1778 0.2794)
						)
					)
					(width 0)
					(fill yes)
				)
			)
		)
	)
	(footprint ""
		(layer "B.Cu")
		(at 162.306 -92.7354)
		(property "Reference" "C714"
			(at 0 0 0)
			(layer "B.SilkS")
			(hide yes)
			(effects
				(font
					(size 1.27 1.27)
				)
				(justify mirror)
			)
		)
		(property "Value" "SCD1U10V2KX-5GP"
			(at -1.1811 -2.7051 0)
			(unlocked yes)
			(layer "B.Fab")
			(hide yes)
			(effects
				(font
					(size 1.016 1.016)
					(thickness 0.1524)
				)
				(justify mirror)
			)
		)
		(property "Device Type" "C402H22"
			(at -1.1811 -4.2291 0)
			(unlocked yes)
			(layer "B.Fab")
			(hide yes)
			(effects
				(font
					(size 1.016 1.016)
					(thickness 0.1524)
				)
				(justify mirror)
			)
		)
		(duplicate_pad_numbers_are_jumpers no)
		(fp_rect
			(start 0.4318 0.9525)
			(end -0.4318 -0.9525)
			(stroke
				(width 0)
				(type default)
			)
			(fill no)
			(layer "B.CrtYd")
		)
		(fp_rect
			(start 0.4318 0.9525)
			(end -0.4318 -0.9525)
			(stroke
				(width 0)
				(type default)
			)
			(fill no)
			(layer "B.Fab")
		)
		(pad "1" smd custom
			(at 0 -0.4445 180)
			(size 0.1524 0.1524)
			(layers "B.Cu" "B.Mask" "B.Paste")
			(net "P1V8_CLKGEN")
			(options
				(clearance outline)
				(anchor circle)
			)
			(primitives
				(gr_poly
					(pts
						(arc
							(start 0.3048 0.2032)
							(mid 0.275042 0.275042)
							(end 0.2032 0.3048)
						)
						(arc
							(start -0.2032 0.3048)
							(mid -0.275042 0.275042)
							(end -0.3048 0.2032)
						)
						(arc
							(start -0.3048 -0.2032)
							(mid -0.275042 -0.275042)
							(end -0.2032 -0.3048)
						)
						(arc
							(start 0.2032 -0.3048)
							(mid 0.275042 -0.275042)
							(end 0.3048 -0.2032)
						)
					)
					(width 0)
					(fill yes)
				)
			)
		)
		(pad "2" smd custom
			(at 0 0.4445 180)
			(size 0.1524 0.1524)
			(layers "B.Cu" "B.Mask" "B.Paste")
			(net "GND")
			(options
				(clearance outline)
				(anchor circle)
			)
			(primitives
				(gr_poly
					(pts
						(arc
							(start 0.3048 0.2032)
							(mid 0.275042 0.275042)
							(end 0.2032 0.3048)
						)
						(arc
							(start -0.2032 0.3048)
							(mid -0.275042 0.275042)
							(end -0.3048 0.2032)
						)
						(arc
							(start -0.3048 -0.2032)
							(mid -0.275042 -0.275042)
							(end -0.2032 -0.3048)
						)
						(arc
							(start 0.2032 -0.3048)
							(mid 0.275042 -0.275042)
							(end 0.3048 -0.2032)
						)
					)
					(width 0)
					(fill yes)
				)
			)
		)
	)
	(footprint ""
		(layer "B.Cu")
		(at 35.774884 -109.319314 -90)
		(property "Reference" "R679"
			(at 0 0 90)
			(layer "B.SilkS")
			(hide yes)
			(effects
				(font
					(size 1.27 1.27)
				)
				(justify mirror)
			)
		)
		(property "Value" "0R2J-2-GP"
			(at -0.064008 -3.993896 270)
			(unlocked yes)
			(layer "B.Fab")
			(hide yes)
			(effects
				(font
					(size 1.016 1.016)
					(thickness 0.1524)
				)
				(justify mirror)
			)
		)
		(property "Device Type" "R402H16"
			(at -0.064008 -5.517896 270)
			(unlocked yes)
			(layer "B.Fab")
			(hide yes)
			(effects
				(font
					(size 1.016 1.016)
					(thickness 0.1524)
				)
				(justify mirror)
			)
		)
		(duplicate_pad_numbers_are_jumpers no)
		(fp_line
			(start -0.508 -0.9398)
			(end 0.508 -0.9398)
			(stroke
				(width 0.1524)
				(type default)
			)
			(layer "B.SilkS")
		)
		(fp_line
			(start 0.508 -0.9398)
			(end 0.508 0.9398)
			(stroke
				(width 0.1524)
				(type default)
			)
			(layer "B.SilkS")
		)
		(fp_rect
			(start 0.508 0.9398)
			(end -0.508 -0.9398)
			(stroke
				(width 0)
				(type default)
			)
			(fill no)
			(layer "B.CrtYd")
		)
		(fp_rect
			(start 0.508 0.9398)
			(end -0.508 -0.9398)
			(stroke
				(width 0)
				(type default)
			)
			(fill no)
			(layer "B.Fab")
		)
		(pad "1" smd custom
			(at 0 -0.4445 90)
			(size 0.1397 0.1397)
			(layers "B.Cu" "B.Mask" "B.Paste")
			(net "BMC_RXCK_R")
			(options
				(clearance outline)
				(anchor circle)
			)
			(primitives
				(gr_poly
					(pts
						(arc
							(start -0.1778 0.2794)
							(mid -0.249642 0.249642)
							(end -0.2794 0.1778)
						)
						(arc
							(start -0.2794 -0.1778)
							(mid -0.249642 -0.249642)
							(end -0.1778 -0.2794)
						)
						(arc
							(start 0.1778 -0.2794)
							(mid 0.249642 -0.249642)
							(end 0.2794 -0.1778)
						)
						(arc
							(start 0.2794 0.1778)
							(mid 0.249642 0.249642)
							(end 0.1778 0.2794)
						)
					)
					(width 0)
					(fill yes)
				)
			)
		)
		(pad "2" smd custom
			(at 0 0.4445 90)
			(size 0.1397 0.1397)
			(layers "B.Cu" "B.Mask" "B.Paste")
			(net "CLK_50M_BMC0")
			(options
				(clearance outline)
				(anchor circle)
			)
			(primitives
				(gr_poly
					(pts
						(arc
							(start -0.1778 0.2794)
							(mid -0.249642 0.249642)
							(end -0.2794 0.1778)
						)
						(arc
							(start -0.2794 -0.1778)
							(mid -0.249642 -0.249642)
							(end -0.1778 -0.2794)
						)
						(arc
							(start 0.1778 -0.2794)
							(mid 0.249642 -0.249642)
							(end 0.2794 -0.1778)
						)
						(arc
							(start 0.2794 0.1778)
							(mid 0.249642 0.249642)
							(end 0.1778 0.2794)
						)
					)
					(width 0)
					(fill yes)
				)
			)
		)
	)
)
